# T6G (Grand Teton) — schematic netlist excerpt (pin names and nets, part order shuffled) for the footprints in the layout excerpt that follows; sources: Cadence DE-HDL packaged netlist, KiCad conversion of 04192023_DAF0TMB3IC0_F0TG_MB_C_brd_V02_OCP.brd

R3657  Q_RES  10K 1% EMPTY  pkg 0402LF  page 234 : A = P3V3_AUX ; B = USB_HUB_OVCUR2
R6327  Q_RES  4.7K 1% EMPTY  pkg 0402LF  page 178 : A = P3V3_AUX ; B = USB_HUB2_MRP_PROG_FUNC6

(kicad_pcb
	(version 20260206)
	(generator "pcbnew")
	(generator_version "10.0")
	(general
		(thickness 1.6)
		(legacy_teardrops no)
	)
	(paper "A4")
	(title_block
		(title "04192023_DAF0TMB3IC0_F0TG_MB_C_brd_V02_OCP.brd")
		(comment 1 "Grand Teton / footprints 4629-4630 of 8354")
	)
	(layers
		(0 "F.Cu" signal "TOP")
		(4 "In1.Cu" signal "GND")
		(6 "In2.Cu" signal "IN1")
		(8 "In3.Cu" signal "GND1")
		(10 "In4.Cu" signal "IN2")
		(12 "In5.Cu" signal "GND2")
		(14 "In6.Cu" signal "IN3")
		(16 "In7.Cu" signal "GND3")
		(18 "In8.Cu" signal "VCC")
		(20 "In9.Cu" signal "VCC1")
		(22 "In10.Cu" signal "GND4")
		(24 "In11.Cu" signal "IN4")
		(26 "In12.Cu" signal "GND5")
		(28 "In13.Cu" signal "IN5")
		(30 "In14.Cu" signal "GND6")
		(32 "In15.Cu" signal "IN6")
		(34 "In16.Cu" signal "GND7")
		(2 "B.Cu" signal "BOTTOM")
		(9 "F.Adhes" user "F.Adhesive")
		(11 "B.Adhes" user "B.Adhesive")
		(13 "F.Paste" user "Package Geometry/Pastemask Top")
		(15 "B.Paste" user "Package Geometry/Pastemask Bottom")
		(5 "F.SilkS" user "Ref Des/Silkscreen Top")
		(7 "B.SilkS" user "Ref Des/Silkscreen Bottom")
		(1 "F.Mask" user "Board Geometry/Soldermask Top")
		(3 "B.Mask" user "Board Geometry/Soldermask Bottom")
		(17 "Dwgs.User" user "User.Drawings")
		(19 "Cmts.User" user "User.Comments")
		(21 "Eco1.User" user "User.Eco1")
		(23 "Eco2.User" user "User.Eco2")
		(25 "Edge.Cuts" user "Board Geometry/Outline")
		(27 "Margin" user)
		(31 "F.CrtYd" user "Package Geometry/Place Bound Top")
		(29 "B.CrtYd" user "Package Geometry/Place Bound Bottom")
		(35 "F.Fab" user "Ref Des/Assembly Top")
		(33 "B.Fab" user "Ref Des/Assembly Bottom")
	)
	(footprint ""
		(layer "F.Cu")
		(at 21.176996 -99.413314 180)
		(property "Reference" "R3657"
			(at 0 0 180)
			(layer "F.SilkS")
			(hide yes)
			(effects
				(font
					(size 1.27 1.27)
				)
			)
		)
		(property "Value" ""
			(at 0 0 180)
			(layer "F.Fab")
			(effects
				(font
					(size 1.27 1.27)
				)
			)
		)
		(duplicate_pad_numbers_are_jumpers no)
		(fp_line
			(start 0.7874 0.4064)
			(end -0.7874 0.4064)
			(stroke
				(width 0.1524)
				(type default)
			)
			(layer "F.SilkS")
		)
		(fp_line
			(start 0.7874 -0.4064)
			(end 0.7874 0.4064)
			(stroke
				(width 0.1524)
				(type default)
			)
			(layer "F.SilkS")
		)
		(fp_line
			(start -0.7874 0.4064)
			(end -0.7874 -0.4064)
			(stroke
				(width 0.1524)
				(type default)
			)
			(layer "F.SilkS")
		)
		(fp_line
			(start -0.7874 -0.4064)
			(end 0.7874 -0.4064)
			(stroke
				(width 0.1524)
				(type default)
			)
			(layer "F.SilkS")
		)
		(fp_line
			(start 0.67945 0.3048)
			(end 0.120396 0.3048)
			(stroke
				(width 0.1)
				(type default)
			)
			(layer "F.Fab")
		)
		(fp_line
			(start 0.67945 -0.3048)
			(end 0.67945 0.3048)
			(stroke
				(width 0.1)
				(type default)
			)
			(layer "F.Fab")
		)
		(fp_line
			(start 0.12065 -0.2794)
			(end 0.12065 -0.3048)
			(stroke
				(width 0.1)
				(type default)
			)
			(layer "F.Fab")
		)
		(fp_line
			(start 0.12065 -0.3048)
			(end 0.67945 -0.3048)
			(stroke
				(width 0.1)
				(type default)
			)
			(layer "F.Fab")
		)
		(fp_line
			(start 0.120396 0.3048)
			(end 0.120396 0.2794)
			(stroke
				(width 0.1)
				(type default)
			)
			(layer "F.Fab")
		)
		(fp_line
			(start 0.120396 0.2794)
			(end -0.12065 0.2794)
			(stroke
				(width 0.1)
				(type default)
			)
			(layer "F.Fab")
		)
		(fp_line
			(start -0.12065 0.3048)
			(end -0.67945 0.3048)
			(stroke
				(width 0.1)
				(type default)
			)
			(layer "F.Fab")
		)
		(fp_line
			(start -0.12065 0.2794)
			(end -0.12065 0.3048)
			(stroke
				(width 0.1)
				(type default)
			)
			(layer "F.Fab")
		)
		(fp_line
			(start -0.12065 -0.2794)
			(end 0.12065 -0.2794)
			(stroke
				(width 0.1)
				(type default)
			)
			(layer "F.Fab")
		)
		(fp_line
			(start -0.12065 -0.305054)
			(end -0.12065 -0.2794)
			(stroke
				(width 0.1)
				(type default)
			)
			(layer "F.Fab")
		)
		(fp_line
			(start -0.67945 0.3048)
			(end -0.67945 -0.305054)
			(stroke
				(width 0.1)
				(type default)
			)
			(layer "F.Fab")
		)
		(fp_line
			(start -0.67945 -0.305054)
			(end -0.12065 -0.305054)
			(stroke
				(width 0.1)
				(type default)
			)
			(layer "F.Fab")
		)
		(pad "1" smd circle
			(at -0.40005 0 180)
			(size 0 0)
			(layers "F.Cu" "F.Mask" "F.Paste")
			(net "P3V3_AUX")
		)
		(pad "2" smd circle
			(at 0.40005 0 180)
			(size 0 0)
			(layers "F.Cu" "F.Mask" "F.Paste")
			(net "USB_HUB_OVCUR2")
		)
	)
	(footprint ""
		(layer "F.Cu")
		(at 103.413814 -37.6682)
		(property "Reference" "R6327"
			(at 0 0 0)
			(layer "F.SilkS")
			(hide yes)
			(effects
				(font
					(size 1.27 1.27)
				)
			)
		)
		(property "Value" ""
			(at 0 0 0)
			(layer "F.Fab")
			(effects
				(font
					(size 1.27 1.27)
				)
			)
		)
		(duplicate_pad_numbers_are_jumpers no)
		(fp_line
			(start -0.7874 -0.4064)
			(end 0.7874 -0.4064)
			(stroke
				(width 0.1524)
				(type default)
			)
			(layer "F.SilkS")
		)
		(fp_line
			(start -0.7874 0.4064)
			(end -0.7874 -0.4064)
			(stroke
				(width 0.1524)
				(type default)
			)
			(layer "F.SilkS")
		)
		(fp_line
			(start 0.7874 -0.4064)
			(end 0.7874 0.4064)
			(stroke
				(width 0.1524)
				(type default)
			)
			(layer "F.SilkS")
		)
		(fp_line
			(start 0.7874 0.4064)
			(end -0.7874 0.4064)
			(stroke
				(width 0.1524)
				(type default)
			)
			(layer "F.SilkS")
		)
		(fp_line
			(start -0.67945 -0.305054)
			(end -0.12065 -0.305054)
			(stroke
				(width 0.1)
				(type default)
			)
			(layer "F.Fab")
		)
		(fp_line
			(start -0.67945 0.3048)
			(end -0.67945 -0.305054)
			(stroke
				(width 0.1)
				(type default)
			)
			(layer "F.Fab")
		)
		(fp_line
			(start -0.12065 -0.305054)
			(end -0.12065 -0.2794)
			(stroke
				(width 0.1)
				(type default)
			)
			(layer "F.Fab")
		)
		(fp_line
			(start -0.12065 -0.2794)
			(end 0.12065 -0.2794)
			(stroke
				(width 0.1)
				(type default)
			)
			(layer "F.Fab")
		)
		(fp_line
			(start -0.12065 0.2794)
			(end -0.12065 0.3048)
			(stroke
				(width 0.1)
				(type default)
			)
			(layer "F.Fab")
		)
		(fp_line
			(start -0.12065 0.3048)
			(end -0.67945 0.3048)
			(stroke
				(width 0.1)
				(type default)
			)
			(layer "F.Fab")
		)
		(fp_line
			(start 0.120396 0.2794)
			(end -0.12065 0.2794)
			(stroke
				(width 0.1)
				(type default)
			)
			(layer "F.Fab")
		)
		(fp_line
			(start 0.120396 0.3048)
			(end 0.120396 0.2794)
			(stroke
				(width 0.1)
				(type default)
			)
			(layer "F.Fab")
		)
		(fp_line
			(start 0.12065 -0.3048)
			(end 0.67945 -0.3048)
			(stroke
				(width 0.1)
				(type default)
			)
			(layer "F.Fab")
		)
		(fp_line
			(start 0.12065 -0.2794)
			(end 0.12065 -0.3048)
			(stroke
				(width 0.1)
				(type default)
			)
			(layer "F.Fab")
		)
		(fp_line
			(start 0.67945 -0.3048)
			(end 0.67945 0.3048)
			(stroke
				(width 0.1)
				(type default)
			)
			(layer "F.Fab")
		)
		(fp_line
			(start 0.67945 0.3048)
			(end 0.120396 0.3048)
			(stroke
				(width 0.1)
				(type default)
			)
			(layer "F.Fab")
		)
		(pad "1" smd circle
			(at -0.40005 0)
			(size 0 0)
			(layers "F.Cu" "F.Mask" "F.Paste")
			(net "P3V3_AUX")
		)
		(pad "2" smd circle
			(at 0.40005 0)
			(size 0 0)
			(layers "F.Cu" "F.Mask" "F.Paste")
			(net "USB_HUB2_MRP_PROG_FUNC6")
		)
	)
)
